(kicad_pcb
	(version 20260206)
	(generator "pcbnew")
	(generator_version "10.0")
	(general
		(thickness 1.6)
		(legacy_teardrops no)
	)
	(paper "A4")
	(title_block
		(title "04192023_DAF0TMB3IC0_F0TG_MB_C_brd_V02_OCP.brd")
		(comment 1 "Grand Teton / footprints 7859-7866 of 8354")
	)
	(layers
		(0 "F.Cu" signal "TOP")
		(4 "In1.Cu" signal "GND")
		(6 "In2.Cu" signal "IN1")
		(8 "In3.Cu" signal "GND1")
		(10 "In4.Cu" signal "IN2")
		(12 "In5.Cu" signal "GND2")
		(14 "In6.Cu" signal "IN3")
		(16 "In7.Cu" signal "GND3")
		(18 "In8.Cu" signal "VCC")
		(20 "In9.Cu" signal "VCC1")
		(22 "In10.Cu" signal "GND4")
		(24 "In11.Cu" signal "IN4")
		(26 "In12.Cu" signal "GND5")
		(28 "In13.Cu" signal "IN5")
		(30 "In14.Cu" signal "GND6")
		(32 "In15.Cu" signal "IN6")
		(34 "In16.Cu" signal "GND7")
		(2 "B.Cu" signal "BOTTOM")
		(9 "F.Adhes" user "F.Adhesive")
		(11 "B.Adhes" user "B.Adhesive")
		(13 "F.Paste" user "Package Geometry/Pastemask Top")
		(15 "B.Paste" user "Package Geometry/Pastemask Bottom")
		(5 "F.SilkS" user "Ref Des/Silkscreen Top")
		(7 "B.SilkS" user "Ref Des/Silkscreen Bottom")
		(1 "F.Mask" user "Board Geometry/Soldermask Top")
		(3 "B.Mask" user "Board Geometry/Soldermask Bottom")
		(17 "Dwgs.User" user "User.Drawings")
		(19 "Cmts.User" user "User.Comments")
		(21 "Eco1.User" user "User.Eco1")
		(23 "Eco2.User" user "User.Eco2")
		(25 "Edge.Cuts" user "Board Geometry/Outline")
		(27 "Margin" user)
		(31 "F.CrtYd" user "Package Geometry/Place Bound Top")
		(29 "B.CrtYd" user "Package Geometry/Place Bound Bottom")
		(35 "F.Fab" user "Ref Des/Assembly Top")
		(33 "B.Fab" user "Ref Des/Assembly Bottom")
	)
	(footprint ""
		(layer "B.Cu")
		(at 400.761962 -314.925964)
		(property "Reference" "C215"
			(at 0 0 0)
			(layer "B.SilkS")
			(hide yes)
			(effects
				(font
					(size 1.27 1.27)
				)
				(justify mirror)
			)
		)
		(property "Value" ""
			(at 0 0 0)
			(layer "B.Fab")
			(effects
				(font
					(size 1.27 1.27)
				)
				(justify mirror)
			)
		)
		(duplicate_pad_numbers_are_jumpers no)
		(fp_line
			(start -0.7874 -0.4064)
			(end -0.7874 0.4064)
			(stroke
				(width 0.1524)
				(type default)
			)
			(layer "B.SilkS")
		)
		(fp_line
			(start -0.7874 0.4064)
			(end 0.7874 0.4064)
			(stroke
				(width 0.1524)
				(type default)
			)
			(layer "B.SilkS")
		)
		(fp_line
			(start 0.7874 -0.4064)
			(end -0.7874 -0.4064)
			(stroke
				(width 0.1524)
				(type default)
			)
			(layer "B.SilkS")
		)
		(fp_line
			(start 0.7874 0.4064)
			(end 0.7874 -0.4064)
			(stroke
				(width 0.1524)
				(type default)
			)
			(layer "B.SilkS")
		)
		(fp_line
			(start -0.67945 -0.3048)
			(end -0.67945 0.3048)
			(stroke
				(width 0.1)
				(type default)
			)
			(layer "B.Fab")
		)
		(fp_line
			(start -0.67945 0.3048)
			(end -0.120396 0.3048)
			(stroke
				(width 0.1)
				(type default)
			)
			(layer "B.Fab")
		)
		(fp_line
			(start -0.12065 -0.3048)
			(end -0.67945 -0.3048)
			(stroke
				(width 0.1)
				(type default)
			)
			(layer "B.Fab")
		)
		(fp_line
			(start -0.12065 -0.2794)
			(end -0.12065 -0.3048)
			(stroke
				(width 0.1)
				(type default)
			)
			(layer "B.Fab")
		)
		(fp_line
			(start -0.120396 0.2794)
			(end 0.12065 0.2794)
			(stroke
				(width 0.1)
				(type default)
			)
			(layer "B.Fab")
		)
		(fp_line
			(start -0.120396 0.3048)
			(end -0.120396 0.2794)
			(stroke
				(width 0.1)
				(type default)
			)
			(layer "B.Fab")
		)
		(fp_line
			(start 0.12065 -0.305054)
			(end 0.12065 -0.2794)
			(stroke
				(width 0.1)
				(type default)
			)
			(layer "B.Fab")
		)
		(fp_line
			(start 0.12065 -0.2794)
			(end -0.12065 -0.2794)
			(stroke
				(width 0.1)
				(type default)
			)
			(layer "B.Fab")
		)
		(fp_line
			(start 0.12065 0.2794)
			(end 0.12065 0.3048)
			(stroke
				(width 0.1)
				(type default)
			)
			(layer "B.Fab")
		)
		(fp_line
			(start 0.12065 0.3048)
			(end 0.67945 0.3048)
			(stroke
				(width 0.1)
				(type default)
			)
			(layer "B.Fab")
		)
		(fp_line
			(start 0.67945 -0.305054)
			(end 0.12065 -0.305054)
			(stroke
				(width 0.1)
				(type default)
			)
			(layer "B.Fab")
		)
		(fp_line
			(start 0.67945 0.3048)
			(end 0.67945 -0.305054)
			(stroke
				(width 0.1)
				(type default)
			)
			(layer "B.Fab")
		)
		(pad "1" smd circle
			(at 0.40005 0 180)
			(size 0 0)
			(layers "B.Cu" "B.Mask" "B.Paste")
			(net "XTAL_CPU0_X32K_X1")
		)
		(pad "2" smd circle
			(at -0.40005 0 180)
			(size 0 0)
			(layers "B.Cu" "B.Mask" "B.Paste")
			(net "GND")
		)
	)
	(footprint ""
		(layer "B.Cu")
		(at 63.619634 -197.202552 180)
		(property "Reference" "R516"
			(at 0 0 0)
			(layer "B.SilkS")
			(hide yes)
			(effects
				(font
					(size 1.27 1.27)
				)
				(justify mirror)
			)
		)
		(property "Value" ""
			(at 0 0 0)
			(layer "B.Fab")
			(effects
				(font
					(size 1.27 1.27)
				)
				(justify mirror)
			)
		)
		(duplicate_pad_numbers_are_jumpers no)
		(fp_line
			(start 0.7874 0.4064)
			(end 0.7874 -0.4064)
			(stroke
				(width 0.1524)
				(type default)
			)
			(layer "B.SilkS")
		)
		(fp_line
			(start 0.7874 -0.4064)
			(end -0.7874 -0.4064)
			(stroke
				(width 0.1524)
				(type default)
			)
			(layer "B.SilkS")
		)
		(fp_line
			(start -0.7874 0.4064)
			(end 0.7874 0.4064)
			(stroke
				(width 0.1524)
				(type default)
			)
			(layer "B.SilkS")
		)
		(fp_line
			(start -0.7874 -0.4064)
			(end -0.7874 0.4064)
			(stroke
				(width 0.1524)
				(type default)
			)
			(layer "B.SilkS")
		)
		(fp_line
			(start 0.67945 0.3048)
			(end 0.67945 -0.305054)
			(stroke
				(width 0.1)
				(type default)
			)
			(layer "B.Fab")
		)
		(fp_line
			(start 0.67945 -0.305054)
			(end 0.12065 -0.305054)
			(stroke
				(width 0.1)
				(type default)
			)
			(layer "B.Fab")
		)
		(fp_line
			(start 0.12065 0.3048)
			(end 0.67945 0.3048)
			(stroke
				(width 0.1)
				(type default)
			)
			(layer "B.Fab")
		)
		(fp_line
			(start 0.12065 0.2794)
			(end 0.12065 0.3048)
			(stroke
				(width 0.1)
				(type default)
			)
			(layer "B.Fab")
		)
		(fp_line
			(start 0.12065 -0.2794)
			(end -0.12065 -0.2794)
			(stroke
				(width 0.1)
				(type default)
			)
			(layer "B.Fab")
		)
		(fp_line
			(start 0.12065 -0.305054)
			(end 0.12065 -0.2794)
			(stroke
				(width 0.1)
				(type default)
			)
			(layer "B.Fab")
		)
		(fp_line
			(start -0.120396 0.3048)
			(end -0.120396 0.2794)
			(stroke
				(width 0.1)
				(type default)
			)
			(layer "B.Fab")
		)
		(fp_line
			(start -0.120396 0.2794)
			(end 0.12065 0.2794)
			(stroke
				(width 0.1)
				(type default)
			)
			(layer "B.Fab")
		)
		(fp_line
			(start -0.12065 -0.2794)
			(end -0.12065 -0.3048)
			(stroke
				(width 0.1)
				(type default)
			)
			(layer "B.Fab")
		)
		(fp_line
			(start -0.12065 -0.3048)
			(end -0.67945 -0.3048)
			(stroke
				(width 0.1)
				(type default)
			)
			(layer "B.Fab")
		)
		(fp_line
			(start -0.67945 0.3048)
			(end -0.120396 0.3048)
			(stroke
				(width 0.1)
				(type default)
			)
			(layer "B.Fab")
		)
		(fp_line
			(start -0.67945 -0.3048)
			(end -0.67945 0.3048)
			(stroke
				(width 0.1)
				(type default)
			)
			(layer "B.Fab")
		)
		(pad "1" smd circle
			(at 0.40005 0)
			(size 0 0)
			(layers "B.Cu" "B.Mask" "B.Paste")
			(net "P3V3_AUX")
		)
		(pad "2" smd circle
			(at -0.40005 0)
			(size 0 0)
			(layers "B.Cu" "B.Mask" "B.Paste")
			(net "CPU1_CORETYPE0")
		)
	)
	(footprint ""
		(layer "B.Cu")
		(at 238.708692 -422.849548 90)
		(property "Reference" "C74"
			(at 0 0 90)
			(layer "B.SilkS")
			(hide yes)
			(effects
				(font
					(size 1.27 1.27)
				)
				(justify mirror)
			)
		)
		(property "Value" ""
			(at 0 0 90)
			(layer "B.Fab")
			(effects
				(font
					(size 1.27 1.27)
				)
				(justify mirror)
			)
		)
		(duplicate_pad_numbers_are_jumpers no)
		(fp_line
			(start 0.7874 -0.4064)
			(end -0.7874 -0.4064)
			(stroke
				(width 0.1524)
				(type default)
			)
			(layer "B.SilkS")
		)
		(fp_line
			(start -0.7874 -0.4064)
			(end -0.7874 0.4064)
			(stroke
				(width 0.1524)
				(type default)
			)
			(layer "B.SilkS")
		)
		(fp_line
			(start 0.7874 0.4064)
			(end 0.7874 -0.4064)
			(stroke
				(width 0.1524)
				(type default)
			)
			(layer "B.SilkS")
		)
		(fp_line
			(start -0.7874 0.4064)
			(end 0.7874 0.4064)
			(stroke
				(width 0.1524)
				(type default)
			)
			(layer "B.SilkS")
		)
		(fp_line
			(start 0.67945 -0.305054)
			(end 0.12065 -0.305054)
			(stroke
				(width 0.1)
				(type default)
			)
			(layer "B.Fab")
		)
		(fp_line
			(start 0.12065 -0.305054)
			(end 0.12065 -0.2794)
			(stroke
				(width 0.1)
				(type default)
			)
			(layer "B.Fab")
		)
		(fp_line
			(start -0.12065 -0.3048)
			(end -0.67945 -0.3048)
			(stroke
				(width 0.1)
				(type default)
			)
			(layer "B.Fab")
		)
		(fp_line
			(start -0.67945 -0.3048)
			(end -0.67945 0.3048)
			(stroke
				(width 0.1)
				(type default)
			)
			(layer "B.Fab")
		)
		(fp_line
			(start 0.12065 -0.2794)
			(end -0.12065 -0.2794)
			(stroke
				(width 0.1)
				(type default)
			)
			(layer "B.Fab")
		)
		(fp_line
			(start -0.12065 -0.2794)
			(end -0.12065 -0.3048)
			(stroke
				(width 0.1)
				(type default)
			)
			(layer "B.Fab")
		)
		(fp_line
			(start 0.12065 0.2794)
			(end 0.12065 0.3048)
			(stroke
				(width 0.1)
				(type default)
			)
			(layer "B.Fab")
		)
		(fp_line
			(start -0.120396 0.2794)
			(end 0.12065 0.2794)
			(stroke
				(width 0.1)
				(type default)
			)
			(layer "B.Fab")
		)
		(fp_line
			(start 0.67945 0.3048)
			(end 0.67945 -0.305054)
			(stroke
				(width 0.1)
				(type default)
			)
			(layer "B.Fab")
		)
		(fp_line
			(start 0.12065 0.3048)
			(end 0.67945 0.3048)
			(stroke
				(width 0.1)
				(type default)
			)
			(layer "B.Fab")
		)
		(fp_line
			(start -0.120396 0.3048)
			(end -0.120396 0.2794)
			(stroke
				(width 0.1)
				(type default)
			)
			(layer "B.Fab")
		)
		(fp_line
			(start -0.67945 0.3048)
			(end -0.120396 0.3048)
			(stroke
				(width 0.1)
				(type default)
			)
			(layer "B.Fab")
		)
		(pad "1" smd circle
			(at 0.40005 0 270)
			(size 0 0)
			(layers "B.Cu" "B.Mask" "B.Paste")
			(net "RST_SMB_SWITCH_R_N")
		)
		(pad "2" smd circle
			(at -0.40005 0 270)
			(size 0 0)
			(layers "B.Cu" "B.Mask" "B.Paste")
			(net "GND")
		)
	)
	(footprint ""
		(layer "B.Cu")
		(at 59.51855 -388.011162 -90)
		(property "Reference" "C137"
			(at 0 0 90)
			(layer "B.SilkS")
			(hide yes)
			(effects
				(font
					(size 1.27 1.27)
				)
				(justify mirror)
			)
		)
		(property "Value" ""
			(at 0 0 90)
			(layer "B.Fab")
			(effects
				(font
					(size 1.27 1.27)
				)
				(justify mirror)
			)
		)
		(duplicate_pad_numbers_are_jumpers no)
		(fp_line
			(start -0.299974 0.150114)
			(end 0.299974 0.150114)
			(stroke
				(width 0.1)
				(type default)
			)
			(layer "B.Fab")
		)
		(fp_line
			(start 0.299974 0.150114)
			(end 0.299974 -0.150114)
			(stroke
				(width 0.1)
				(type default)
			)
			(layer "B.Fab")
		)
		(fp_line
			(start -0.299974 -0.150114)
			(end -0.299974 0.150114)
			(stroke
				(width 0.1)
				(type default)
			)
			(layer "B.Fab")
		)
		(fp_line
			(start 0.299974 -0.150114)
			(end -0.299974 -0.150114)
			(stroke
				(width 0.1)
				(type default)
			)
			(layer "B.Fab")
		)
		(pad "1" smd rect
			(at 0.2667 0 90)
			(size 0.3048 0.381)
			(layers "B.Cu" "B.Mask" "B.Paste")
			(net "P0V9_CPU1_RT_2D")
		)
		(pad "2" smd rect
			(at -0.2667 0 90)
			(size 0.3048 0.381)
			(layers "B.Cu" "B.Mask" "B.Paste")
			(net "GND")
		)
	)
	(footprint ""
		(layer "B.Cu")
		(at 458.346302 -405.972264 180)
		(property "Reference" "PC6817"
			(at 0 0 0)
			(layer "B.SilkS")
			(hide yes)
			(effects
				(font
					(size 1.27 1.27)
				)
				(justify mirror)
			)
		)
		(property "Value" ""
			(at 0 0 0)
			(layer "B.Fab")
			(effects
				(font
					(size 1.27 1.27)
				)
				(justify mirror)
			)
		)
		(duplicate_pad_numbers_are_jumpers no)
		(fp_line
			(start 1.524 0.762)
			(end 1.524 -0.762)
			(stroke
				(width 0.1524)
				(type default)
			)
			(layer "B.SilkS")
		)
		(fp_line
			(start 1.524 -0.762)
			(end -1.524 -0.762)
			(stroke
				(width 0.1524)
				(type default)
			)
			(layer "B.SilkS")
		)
		(fp_line
			(start -1.524 0.762)
			(end 1.524 0.762)
			(stroke
				(width 0.1524)
				(type default)
			)
			(layer "B.SilkS")
		)
		(fp_line
			(start -1.524 -0.762)
			(end -1.524 0.762)
			(stroke
				(width 0.1524)
				(type default)
			)
			(layer "B.SilkS")
		)
		(fp_line
			(start 1.1049 0.724916)
			(end -1.1049 0.724916)
			(stroke
				(width 0.1)
				(type default)
			)
			(layer "B.Fab")
		)
		(fp_line
			(start 1.1049 -0.724916)
			(end 1.1049 0.724916)
			(stroke
				(width 0.1)
				(type default)
			)
			(layer "B.Fab")
		)
		(fp_line
			(start -1.1049 0.724916)
			(end -1.1049 -0.724916)
			(stroke
				(width 0.1)
				(type default)
			)
			(layer "B.Fab")
		)
		(fp_line
			(start -1.1049 -0.724916)
			(end 1.1049 -0.724916)
			(stroke
				(width 0.1)
				(type default)
			)
			(layer "B.Fab")
		)
		(pad "1" smd rect
			(at 0.889 0 180)
			(size 1.016 1.27)
			(layers "B.Cu" "B.Mask" "B.Paste")
			(net "SW_P12V_AUX_P0V9_RETIMER_CPU0_FLT")
		)
		(pad "2" smd rect
			(at -0.889 0 180)
			(size 1.016 1.27)
			(layers "B.Cu" "B.Mask" "B.Paste")
			(net "GND")
		)
	)
	(footprint ""
		(layer "B.Cu")
		(at 321.51828 -396.393162 -90)
		(property "Reference" "C585"
			(at 0 0 90)
			(layer "B.SilkS")
			(hide yes)
			(effects
				(font
					(size 1.27 1.27)
				)
				(justify mirror)
			)
		)
		(property "Value" ""
			(at 0 0 90)
			(layer "B.Fab")
			(effects
				(font
					(size 1.27 1.27)
				)
				(justify mirror)
			)
		)
		(duplicate_pad_numbers_are_jumpers no)
		(fp_line
			(start -0.299974 0.150114)
			(end 0.299974 0.150114)
			(stroke
				(width 0.1)
				(type default)
			)
			(layer "B.Fab")
		)
		(fp_line
			(start 0.299974 0.150114)
			(end 0.299974 -0.150114)
			(stroke
				(width 0.1)
				(type default)
			)
			(layer "B.Fab")
		)
		(fp_line
			(start -0.299974 -0.150114)
			(end -0.299974 0.150114)
			(stroke
				(width 0.1)
				(type default)
			)
			(layer "B.Fab")
		)
		(fp_line
			(start 0.299974 -0.150114)
			(end -0.299974 -0.150114)
			(stroke
				(width 0.1)
				(type default)
			)
			(layer "B.Fab")
		)
		(pad "1" smd rect
			(at 0.2667 0 90)
			(size 0.3048 0.381)
			(layers "B.Cu" "B.Mask" "B.Paste")
			(net "P0V9_CPU0_RT0_2A")
		)
		(pad "2" smd rect
			(at -0.2667 0 90)
			(size 0.3048 0.381)
			(layers "B.Cu" "B.Mask" "B.Paste")
			(net "GND")
		)
	)
	(footprint ""
		(layer "B.Cu")
		(at 257.719576 -326.335898 180)
		(property "Reference" "C1076"
			(at 0 0 0)
			(layer "B.SilkS")
			(hide yes)
			(effects
				(font
					(size 1.27 1.27)
				)
				(justify mirror)
			)
		)
		(property "Value" ""
			(at 0 0 0)
			(layer "B.Fab")
			(effects
				(font
					(size 1.27 1.27)
				)
				(justify mirror)
			)
		)
		(duplicate_pad_numbers_are_jumpers no)
		(fp_line
			(start 1.524 0.762)
			(end 1.524 -0.762)
			(stroke
				(width 0.1524)
				(type default)
			)
			(layer "B.SilkS")
		)
		(fp_line
			(start 1.524 -0.762)
			(end -1.524 -0.762)
			(stroke
				(width 0.1524)
				(type default)
			)
			(layer "B.SilkS")
		)
		(fp_line
			(start -1.524 0.762)
			(end 1.524 0.762)
			(stroke
				(width 0.1524)
				(type default)
			)
			(layer "B.SilkS")
		)
		(fp_line
			(start -1.524 -0.762)
			(end -1.524 0.762)
			(stroke
				(width 0.1524)
				(type default)
			)
			(layer "B.SilkS")
		)
		(fp_line
			(start 1.1049 0.724916)
			(end -1.1049 0.724916)
			(stroke
				(width 0.1)
				(type default)
			)
			(layer "B.Fab")
		)
		(fp_line
			(start 1.1049 -0.724916)
			(end 1.1049 0.724916)
			(stroke
				(width 0.1)
				(type default)
			)
			(layer "B.Fab")
		)
		(fp_line
			(start -1.1049 0.724916)
			(end -1.1049 -0.724916)
			(stroke
				(width 0.1)
				(type default)
			)
			(layer "B.Fab")
		)
		(fp_line
			(start -1.1049 -0.724916)
			(end 1.1049 -0.724916)
			(stroke
				(width 0.1)
				(type default)
			)
			(layer "B.Fab")
		)
		(pad "1" smd rect
			(at 0.889 0 180)
			(size 1.016 1.27)
			(layers "B.Cu" "B.Mask" "B.Paste")
			(net "MAX11617_2_VREF")
		)
		(pad "2" smd rect
			(at -0.889 0 180)
			(size 1.016 1.27)
			(layers "B.Cu" "B.Mask" "B.Paste")
			(net "GND")
		)
	)
	(footprint ""
		(layer "B.Cu")
		(at 146.220434 -203.679552 90)
		(property "Reference" "R527"
			(at 0 0 90)
			(layer "B.SilkS")
			(hide yes)
			(effects
				(font
					(size 1.27 1.27)
				)
				(justify mirror)
			)
		)
		(property "Value" ""
			(at 0 0 90)
			(layer "B.Fab")
			(effects
				(font
					(size 1.27 1.27)
				)
				(justify mirror)
			)
		)
		(duplicate_pad_numbers_are_jumpers no)
		(fp_line
			(start 0.7874 -0.4064)
			(end -0.7874 -0.4064)
			(stroke
				(width 0.1524)
				(type default)
			)
			(layer "B.SilkS")
		)
		(fp_line
			(start -0.7874 -0.4064)
			(end -0.7874 0.4064)
			(stroke
				(width 0.1524)
				(type default)
			)
			(layer "B.SilkS")
		)
		(fp_line
			(start 0.7874 0.4064)
			(end 0.7874 -0.4064)
			(stroke
				(width 0.1524)
				(type default)
			)
			(layer "B.SilkS")
		)
		(fp_line
			(start -0.7874 0.4064)
			(end 0.7874 0.4064)
			(stroke
				(width 0.1524)
				(type default)
			)
			(layer "B.SilkS")
		)
		(fp_line
			(start 0.67945 -0.305054)
			(end 0.12065 -0.305054)
			(stroke
				(width 0.1)
				(type default)
			)
			(layer "B.Fab")
		)
		(fp_line
			(start 0.12065 -0.305054)
			(end 0.12065 -0.2794)
			(stroke
				(width 0.1)
				(type default)
			)
			(layer "B.Fab")
		)
		(fp_line
			(start -0.12065 -0.3048)
			(end -0.67945 -0.3048)
			(stroke
				(width 0.1)
				(type default)
			)
			(layer "B.Fab")
		)
		(fp_line
			(start -0.67945 -0.3048)
			(end -0.67945 0.3048)
			(stroke
				(width 0.1)
				(type default)
			)
			(layer "B.Fab")
		)
		(fp_line
			(start 0.12065 -0.2794)
			(end -0.12065 -0.2794)
			(stroke
				(width 0.1)
				(type default)
			)
			(layer "B.Fab")
		)
		(fp_line
			(start -0.12065 -0.2794)
			(end -0.12065 -0.3048)
			(stroke
				(width 0.1)
				(type default)
			)
			(layer "B.Fab")
		)
		(fp_line
			(start 0.12065 0.2794)
			(end 0.12065 0.3048)
			(stroke
				(width 0.1)
				(type default)
			)
			(layer "B.Fab")
		)
		(fp_line
			(start -0.120396 0.2794)
			(end 0.12065 0.2794)
			(stroke
				(width 0.1)
				(type default)
			)
			(layer "B.Fab")
		)
		(fp_line
			(start 0.67945 0.3048)
			(end 0.67945 -0.305054)
			(stroke
				(width 0.1)
				(type default)
			)
			(layer "B.Fab")
		)
		(fp_line
			(start 0.12065 0.3048)
			(end 0.67945 0.3048)
			(stroke
				(width 0.1)
				(type default)
			)
			(layer "B.Fab")
		)
		(fp_line
			(start -0.120396 0.3048)
			(end -0.120396 0.2794)
			(stroke
				(width 0.1)
				(type default)
			)
			(layer "B.Fab")
		)
		(fp_line
			(start -0.67945 0.3048)
			(end -0.120396 0.3048)
			(stroke
				(width 0.1)
				(type default)
			)
			(layer "B.Fab")
		)
		(pad "1" smd circle
			(at 0.40005 0 270)
			(size 0 0)
			(layers "B.Cu" "B.Mask" "B.Paste")
			(net "PVDD18_S5_P1")
		)
		(pad "2" smd circle
			(at -0.40005 0 270)
			(size 0 0)
			(layers "B.Cu" "B.Mask" "B.Paste")
			(net "JTAG_CPU1_TMS")
		)
	)
)
